# SCM (Grand Teton) — schematic netlist excerpt (pin names and nets, part order shuffled) for the footprints in the layout excerpt that follows; sources: Cadence DE-HDL packaged netlist, KiCad conversion of 12092022_DA0F0TMDCD0_F0T_Management_Board_D_brd_V3_OCP.brd

C122  Q_CAP  1UF 25V 10% X6S  pkg C0402  page 16 : A = P1V2_AUX ; B = GND
C24  Q_CAP  0.1UF 25V 10% X7R  pkg 0402  page 12 : A = P2E_PCH_TX_DP ; B = P2E_PCH_TX_C_DP

(kicad_pcb
	(version 20260206)
	(generator "pcbnew")
	(generator_version "10.0")
	(general
		(thickness 1.6)
		(legacy_teardrops no)
	)
	(paper "A4")
	(title_block
		(title "12092022_DA0F0TMDCD0_F0T_Management_Board_D_brd_V3_OCP.brd")
		(comment 1 "Grand Teton / footprints 1225-1226 of 1440")
	)
	(layers
		(0 "F.Cu" signal "TOP")
		(4 "In1.Cu" signal "GND")
		(6 "In2.Cu" signal "IN1")
		(8 "In3.Cu" signal "GND1")
		(10 "In4.Cu" signal "IN2")
		(12 "In5.Cu" signal "VCC")
		(14 "In6.Cu" signal "VCC1")
		(16 "In7.Cu" signal "IN3")
		(18 "In8.Cu" signal "GND2")
		(20 "In9.Cu" signal "IN4")
		(22 "In10.Cu" signal "GND3")
		(2 "B.Cu" signal "BOTTOM")
		(9 "F.Adhes" user "F.Adhesive")
		(11 "B.Adhes" user "B.Adhesive")
		(13 "F.Paste" user "Package Geometry/Pastemask Top")
		(15 "B.Paste" user "Package Geometry/Pastemask Bottom")
		(5 "F.SilkS" user "Ref Des/Silkscreen Top")
		(7 "B.SilkS" user "Ref Des/Silkscreen Bottom")
		(1 "F.Mask" user "Board Geometry/Soldermask Top")
		(3 "B.Mask" user "Board Geometry/Soldermask Bottom")
		(17 "Dwgs.User" user "User.Drawings")
		(19 "Cmts.User" user "User.Comments")
		(21 "Eco1.User" user "User.Eco1")
		(23 "Eco2.User" user "User.Eco2")
		(25 "Edge.Cuts" user "Board Geometry/Outline")
		(27 "Margin" user)
		(31 "F.CrtYd" user "Package Geometry/Place Bound Top")
		(29 "B.CrtYd" user "Package Geometry/Place Bound Bottom")
		(35 "F.Fab" user "Ref Des/Assembly Top")
		(33 "B.Fab" user "Ref Des/Assembly Bottom")
	)
	(footprint ""
		(layer "B.Cu")
		(at 51.682904 -47.617126 -90)
		(property "Reference" "C122"
			(at 0 0 90)
			(layer "B.SilkS")
			(hide yes)
			(effects
				(font
					(size 1.27 1.27)
				)
				(justify mirror)
			)
		)
		(property "Value" ""
			(at 0 0 90)
			(layer "B.Fab")
			(effects
				(font
					(size 1.27 1.27)
				)
				(justify mirror)
			)
		)
		(duplicate_pad_numbers_are_jumpers no)
		(fp_line
			(start -0.7874 0.4064)
			(end 0.7874 0.4064)
			(stroke
				(width 0.1524)
				(type default)
			)
			(layer "B.SilkS")
		)
		(fp_line
			(start 0.7874 0.4064)
			(end 0.7874 -0.4064)
			(stroke
				(width 0.1524)
				(type default)
			)
			(layer "B.SilkS")
		)
		(fp_line
			(start -0.7874 -0.4064)
			(end -0.7874 0.4064)
			(stroke
				(width 0.1524)
				(type default)
			)
			(layer "B.SilkS")
		)
		(fp_line
			(start 0.7874 -0.4064)
			(end -0.7874 -0.4064)
			(stroke
				(width 0.1524)
				(type default)
			)
			(layer "B.SilkS")
		)
		(fp_line
			(start -0.67945 0.3048)
			(end -0.120396 0.3048)
			(stroke
				(width 0.1)
				(type default)
			)
			(layer "B.Fab")
		)
		(fp_line
			(start -0.120396 0.3048)
			(end -0.120396 0.2794)
			(stroke
				(width 0.1)
				(type default)
			)
			(layer "B.Fab")
		)
		(fp_line
			(start 0.12065 0.3048)
			(end 0.67945 0.3048)
			(stroke
				(width 0.1)
				(type default)
			)
			(layer "B.Fab")
		)
		(fp_line
			(start 0.67945 0.3048)
			(end 0.67945 -0.305054)
			(stroke
				(width 0.1)
				(type default)
			)
			(layer "B.Fab")
		)
		(fp_line
			(start -0.120396 0.2794)
			(end 0.12065 0.2794)
			(stroke
				(width 0.1)
				(type default)
			)
			(layer "B.Fab")
		)
		(fp_line
			(start 0.12065 0.2794)
			(end 0.12065 0.3048)
			(stroke
				(width 0.1)
				(type default)
			)
			(layer "B.Fab")
		)
		(fp_line
			(start -0.12065 -0.2794)
			(end -0.12065 -0.3048)
			(stroke
				(width 0.1)
				(type default)
			)
			(layer "B.Fab")
		)
		(fp_line
			(start 0.12065 -0.2794)
			(end -0.12065 -0.2794)
			(stroke
				(width 0.1)
				(type default)
			)
			(layer "B.Fab")
		)
		(fp_line
			(start -0.67945 -0.3048)
			(end -0.67945 0.3048)
			(stroke
				(width 0.1)
				(type default)
			)
			(layer "B.Fab")
		)
		(fp_line
			(start -0.12065 -0.3048)
			(end -0.67945 -0.3048)
			(stroke
				(width 0.1)
				(type default)
			)
			(layer "B.Fab")
		)
		(fp_line
			(start 0.12065 -0.305054)
			(end 0.12065 -0.2794)
			(stroke
				(width 0.1)
				(type default)
			)
			(layer "B.Fab")
		)
		(fp_line
			(start 0.67945 -0.305054)
			(end 0.12065 -0.305054)
			(stroke
				(width 0.1)
				(type default)
			)
			(layer "B.Fab")
		)
		(pad "1" smd circle
			(at 0.40005 0 90)
			(size 0 0)
			(layers "B.Cu" "B.Mask" "B.Paste")
			(net "P1V2_AUX")
		)
		(pad "2" smd circle
			(at -0.40005 0 90)
			(size 0 0)
			(layers "B.Cu" "B.Mask" "B.Paste")
			(net "GND")
		)
	)
	(footprint ""
		(layer "B.Cu")
		(at 62.59322 -61.985906 -90)
		(property "Reference" "C24"
			(at 0 0 90)
			(layer "B.SilkS")
			(hide yes)
			(effects
				(font
					(size 1.27 1.27)
				)
				(justify mirror)
			)
		)
		(property "Value" ""
			(at 0 0 90)
			(layer "B.Fab")
			(effects
				(font
					(size 1.27 1.27)
				)
				(justify mirror)
			)
		)
		(duplicate_pad_numbers_are_jumpers no)
		(fp_line
			(start -0.541274 0.4064)
			(end 0.477266 0.4064)
			(stroke
				(width 0.1524)
				(type default)
			)
			(layer "B.SilkS")
		)
		(fp_line
			(start 0.7874 0.05842)
			(end 0.7874 -0.4064)
			(stroke
				(width 0.1524)
				(type default)
			)
			(layer "B.SilkS")
		)
		(fp_line
			(start -0.7874 -0.4064)
			(end -0.7874 0.11684)
			(stroke
				(width 0.1524)
				(type default)
			)
			(layer "B.SilkS")
		)
		(fp_line
			(start 0.7874 -0.4064)
			(end -0.7874 -0.4064)
			(stroke
				(width 0.1524)
				(type default)
			)
			(layer "B.SilkS")
		)
		(fp_line
			(start -0.67945 0.3048)
			(end -0.120396 0.3048)
			(stroke
				(width 0.1)
				(type default)
			)
			(layer "B.Fab")
		)
		(fp_line
			(start -0.120396 0.3048)
			(end -0.120396 0.2794)
			(stroke
				(width 0.1)
				(type default)
			)
			(layer "B.Fab")
		)
		(fp_line
			(start 0.12065 0.3048)
			(end 0.67945 0.3048)
			(stroke
				(width 0.1)
				(type default)
			)
			(layer "B.Fab")
		)
		(fp_line
			(start 0.67945 0.3048)
			(end 0.67945 -0.305054)
			(stroke
				(width 0.1)
				(type default)
			)
			(layer "B.Fab")
		)
		(fp_line
			(start -0.120396 0.2794)
			(end 0.12065 0.2794)
			(stroke
				(width 0.1)
				(type default)
			)
			(layer "B.Fab")
		)
		(fp_line
			(start 0.12065 0.2794)
			(end 0.12065 0.3048)
			(stroke
				(width 0.1)
				(type default)
			)
			(layer "B.Fab")
		)
		(fp_line
			(start -0.12065 -0.2794)
			(end -0.12065 -0.3048)
			(stroke
				(width 0.1)
				(type default)
			)
			(layer "B.Fab")
		)
		(fp_line
			(start 0.12065 -0.2794)
			(end -0.12065 -0.2794)
			(stroke
				(width 0.1)
				(type default)
			)
			(layer "B.Fab")
		)
		(fp_line
			(start -0.67945 -0.3048)
			(end -0.67945 0.3048)
			(stroke
				(width 0.1)
				(type default)
			)
			(layer "B.Fab")
		)
		(fp_line
			(start -0.12065 -0.3048)
			(end -0.67945 -0.3048)
			(stroke
				(width 0.1)
				(type default)
			)
			(layer "B.Fab")
		)
		(fp_line
			(start 0.12065 -0.305054)
			(end 0.12065 -0.2794)
			(stroke
				(width 0.1)
				(type default)
			)
			(layer "B.Fab")
		)
		(fp_line
			(start 0.67945 -0.305054)
			(end 0.12065 -0.305054)
			(stroke
				(width 0.1)
				(type default)
			)
			(layer "B.Fab")
		)
		(pad "1" smd circle
			(at 0.40005 0 90)
			(size 0 0)
			(layers "B.Cu" "B.Mask" "B.Paste")
			(net "P2E_PCH_TX_DP")
		)
		(pad "2" smd circle
			(at -0.40005 0 90)
			(size 0 0)
			(layers "B.Cu" "B.Mask" "B.Paste")
			(net "P2E_PCH_TX_C_DP")
		)
	)
)
